(kicad_pcb
	(version 20260206)
	(generator "pcbnew")
	(generator_version "10.0")
	(general
		(thickness 1.6)
		(legacy_teardrops no)
	)
	(paper "A4")
	(title_block
		(title "03242023_DA0F0TMBIJ0_F0T_Motherboard_J_brd_V01_OCP.brd")
		(comment 1 "Grand Teton / footprints 991-995 of 6105")
	)
	(layers
		(0 "F.Cu" signal "TOP")
		(4 "In1.Cu" signal "GND")
		(6 "In2.Cu" signal "IN1")
		(8 "In3.Cu" signal "GND1")
		(10 "In4.Cu" signal "IN2")
		(12 "In5.Cu" signal "GND2")
		(14 "In6.Cu" signal "IN3")
		(16 "In7.Cu" signal "GND3")
		(18 "In8.Cu" signal "VCC")
		(20 "In9.Cu" signal "VCC1")
		(22 "In10.Cu" signal "GND4")
		(24 "In11.Cu" signal "IN4")
		(26 "In12.Cu" signal "GND5")
		(28 "In13.Cu" signal "IN5")
		(30 "In14.Cu" signal "GND6")
		(32 "In15.Cu" signal "IN6")
		(34 "In16.Cu" signal "GND7")
		(2 "B.Cu" signal "BOTTOM")
		(9 "F.Adhes" user "F.Adhesive")
		(11 "B.Adhes" user "B.Adhesive")
		(13 "F.Paste" user "Package Geometry/Pastemask Top")
		(15 "B.Paste" user "Package Geometry/Pastemask Bottom")
		(5 "F.SilkS" user "Ref Des/Silkscreen Top")
		(7 "B.SilkS" user "Ref Des/Silkscreen Bottom")
		(1 "F.Mask" user "Board Geometry/Soldermask Top")
		(3 "B.Mask" user "Board Geometry/Soldermask Bottom")
		(17 "Dwgs.User" user "User.Drawings")
		(19 "Cmts.User" user "User.Comments")
		(21 "Eco1.User" user "User.Eco1")
		(23 "Eco2.User" user "User.Eco2")
		(25 "Edge.Cuts" user "Board Geometry/Outline")
		(27 "Margin" user)
		(31 "F.CrtYd" user "Package Geometry/Place Bound Top")
		(29 "B.CrtYd" user "Package Geometry/Place Bound Bottom")
		(35 "F.Fab" user "Ref Des/Assembly Top")
		(33 "B.Fab" user "Ref Des/Assembly Bottom")
	)
	(footprint ""
		(layer "F.Cu")
		(at 360.482642 -392.04265)
		(property "Reference" "R4168"
			(at 0 0 0)
			(layer "F.SilkS")
			(hide yes)
			(effects
				(font
					(size 1.27 1.27)
				)
			)
		)
		(property "Value" ""
			(at 0 0 0)
			(layer "F.Fab")
			(effects
				(font
					(size 1.27 1.27)
				)
			)
		)
		(duplicate_pad_numbers_are_jumpers no)
		(fp_line
			(start -0.7874 -0.4064)
			(end 0.7874 -0.4064)
			(stroke
				(width 0.1524)
				(type default)
			)
			(layer "F.SilkS")
		)
		(fp_line
			(start -0.7874 0.4064)
			(end -0.7874 -0.4064)
			(stroke
				(width 0.1524)
				(type default)
			)
			(layer "F.SilkS")
		)
		(fp_line
			(start 0.7874 -0.4064)
			(end 0.7874 0.4064)
			(stroke
				(width 0.1524)
				(type default)
			)
			(layer "F.SilkS")
		)
		(fp_line
			(start 0.7874 0.4064)
			(end -0.7874 0.4064)
			(stroke
				(width 0.1524)
				(type default)
			)
			(layer "F.SilkS")
		)
		(fp_line
			(start -0.67945 -0.305054)
			(end -0.12065 -0.305054)
			(stroke
				(width 0.1)
				(type default)
			)
			(layer "F.Fab")
		)
		(fp_line
			(start -0.67945 0.3048)
			(end -0.67945 -0.305054)
			(stroke
				(width 0.1)
				(type default)
			)
			(layer "F.Fab")
		)
		(fp_line
			(start -0.12065 -0.305054)
			(end -0.12065 -0.2794)
			(stroke
				(width 0.1)
				(type default)
			)
			(layer "F.Fab")
		)
		(fp_line
			(start -0.12065 -0.2794)
			(end 0.12065 -0.2794)
			(stroke
				(width 0.1)
				(type default)
			)
			(layer "F.Fab")
		)
		(fp_line
			(start -0.12065 0.2794)
			(end -0.12065 0.3048)
			(stroke
				(width 0.1)
				(type default)
			)
			(layer "F.Fab")
		)
		(fp_line
			(start -0.12065 0.3048)
			(end -0.67945 0.3048)
			(stroke
				(width 0.1)
				(type default)
			)
			(layer "F.Fab")
		)
		(fp_line
			(start 0.120396 0.2794)
			(end -0.12065 0.2794)
			(stroke
				(width 0.1)
				(type default)
			)
			(layer "F.Fab")
		)
		(fp_line
			(start 0.120396 0.3048)
			(end 0.120396 0.2794)
			(stroke
				(width 0.1)
				(type default)
			)
			(layer "F.Fab")
		)
		(fp_line
			(start 0.12065 -0.3048)
			(end 0.67945 -0.3048)
			(stroke
				(width 0.1)
				(type default)
			)
			(layer "F.Fab")
		)
		(fp_line
			(start 0.12065 -0.2794)
			(end 0.12065 -0.3048)
			(stroke
				(width 0.1)
				(type default)
			)
			(layer "F.Fab")
		)
		(fp_line
			(start 0.67945 -0.3048)
			(end 0.67945 0.3048)
			(stroke
				(width 0.1)
				(type default)
			)
			(layer "F.Fab")
		)
		(fp_line
			(start 0.67945 0.3048)
			(end 0.120396 0.3048)
			(stroke
				(width 0.1)
				(type default)
			)
			(layer "F.Fab")
		)
		(pad "1" smd circle
			(at -0.40005 0)
			(size 0 0)
			(layers "F.Cu" "F.Mask" "F.Paste")
			(net "P3V3_AUX")
		)
		(pad "2" smd circle
			(at 0.40005 0)
			(size 0 0)
			(layers "F.Cu" "F.Mask" "F.Paste")
			(net "GPU_3V3IO_RSVD4_ISO")
		)
	)
	(footprint ""
		(layer "F.Cu")
		(at 55.427118 -408.517344 -90)
		(property "Reference" "C704"
			(at 0 0 270)
			(layer "F.SilkS")
			(hide yes)
			(effects
				(font
					(size 1.27 1.27)
				)
			)
		)
		(property "Value" ""
			(at 0 0 270)
			(layer "F.Fab")
			(effects
				(font
					(size 1.27 1.27)
				)
			)
		)
		(duplicate_pad_numbers_are_jumpers no)
		(fp_line
			(start -0.299974 0.150114)
			(end -0.299974 -0.150114)
			(stroke
				(width 0.1)
				(type default)
			)
			(layer "F.Fab")
		)
		(fp_line
			(start 0.299974 0.150114)
			(end -0.299974 0.150114)
			(stroke
				(width 0.1)
				(type default)
			)
			(layer "F.Fab")
		)
		(fp_line
			(start -0.299974 -0.150114)
			(end 0.299974 -0.150114)
			(stroke
				(width 0.1)
				(type default)
			)
			(layer "F.Fab")
		)
		(fp_line
			(start 0.299974 -0.150114)
			(end 0.299974 0.150114)
			(stroke
				(width 0.1)
				(type default)
			)
			(layer "F.Fab")
		)
		(pad "1" smd rect
			(at -0.2667 0 270)
			(size 0.3048 0.381)
			(layers "F.Cu" "F.Mask" "F.Paste")
			(net "P5E_CPU1_PE4_TX_C_DN<2>")
		)
		(pad "2" smd rect
			(at 0.2667 0 270)
			(size 0.3048 0.381)
			(layers "F.Cu" "F.Mask" "F.Paste")
			(net "P5E_CPU1_PE4_TX_DN<2>")
		)
	)
	(footprint ""
		(layer "F.Cu")
		(at 442.353192 -28.175458 -90)
		(property "Reference" "PU204"
			(at 1.50749 -4.241038 0)
			(unlocked yes)
			(layer "F.SilkS")
			(effects
				(font
					(size 0.7874 0.5842)
					(thickness 0.1524)
				)
				(justify left)
			)
		)
		(property "Value" ""
			(at 0 0 270)
			(layer "F.Fab")
			(effects
				(font
					(size 1.27 1.27)
				)
			)
		)
		(duplicate_pad_numbers_are_jumpers no)
		(fp_line
			(start -1.549908 2.549906)
			(end -0.753872 2.549906)
			(stroke
				(width 0.1524)
				(type default)
			)
			(layer "F.SilkS")
		)
		(fp_line
			(start -0.245872 2.549906)
			(end 0.245872 2.549906)
			(stroke
				(width 0.1524)
				(type default)
			)
			(layer "F.SilkS")
		)
		(fp_line
			(start 0.753872 2.549906)
			(end 1.549908 2.549906)
			(stroke
				(width 0.1524)
				(type default)
			)
			(layer "F.SilkS")
		)
		(fp_line
			(start 1.549908 2.549906)
			(end 1.549908 2.253996)
			(stroke
				(width 0.1524)
				(type default)
			)
			(layer "F.SilkS")
		)
		(fp_line
			(start -1.549908 2.253996)
			(end -1.549908 2.549906)
			(stroke
				(width 0.1524)
				(type default)
			)
			(layer "F.SilkS")
		)
		(fp_line
			(start 1.549908 -2.253996)
			(end 1.549908 -2.549906)
			(stroke
				(width 0.1524)
				(type default)
			)
			(layer "F.SilkS")
		)
		(fp_line
			(start -1.549908 -2.549906)
			(end -1.549908 -2.251964)
			(stroke
				(width 0.1524)
				(type default)
			)
			(layer "F.SilkS")
		)
		(fp_line
			(start -0.752094 -2.549906)
			(end -1.549908 -2.549906)
			(stroke
				(width 0.1524)
				(type default)
			)
			(layer "F.SilkS")
		)
		(fp_line
			(start 0.2413 -2.549906)
			(end -0.2413 -2.549906)
			(stroke
				(width 0.1524)
				(type default)
			)
			(layer "F.SilkS")
		)
		(fp_line
			(start 1.549908 -2.549906)
			(end 0.752094 -2.549906)
			(stroke
				(width 0.1524)
				(type default)
			)
			(layer "F.SilkS")
		)
		(fp_poly
			(pts
				(xy -2.7432 -1.574292) (xy -2.7432 -2.4257) (xy -1.891538 -1.999996)
			)
			(stroke
				(width 0)
				(type default)
			)
			(fill yes)
			(layer "F.SilkS")
		)
		(fp_line
			(start -1.549908 2.549906)
			(end 1.549908 2.549906)
			(stroke
				(width 0.1)
				(type default)
			)
			(layer "F.Fab")
		)
		(fp_line
			(start 1.549908 2.549906)
			(end 1.549908 -2.549906)
			(stroke
				(width 0.1)
				(type default)
			)
			(layer "F.Fab")
		)
		(fp_line
			(start -1.549908 -2.549906)
			(end -1.549908 2.549906)
			(stroke
				(width 0.1)
				(type default)
			)
			(layer "F.Fab")
		)
		(fp_line
			(start 1.549908 -2.549906)
			(end -1.549908 -2.549906)
			(stroke
				(width 0.1)
				(type default)
			)
			(layer "F.Fab")
		)
		(fp_poly
			(pts
				(xy -1.891538 -1.999996) (xy -2.7432 -1.574292) (xy -2.7432 -2.4257)
			)
			(stroke
				(width 0)
				(type default)
			)
			(fill yes)
			(layer "F.Fab")
		)
		(fp_text user "11"
			(at 2.33934 5.998972 0)
			(unlocked yes)
			(layer "F.SilkS")
			(effects
				(font
					(size 0.635 0.4064)
					(thickness 0.1524)
				)
			)
		)
		(fp_text user "10"
			(at -2.46126 2.928112 0)
			(unlocked yes)
			(layer "F.SilkS")
			(effects
				(font
					(size 0.635 0.4064)
					(thickness 0.1524)
				)
			)
		)
		(fp_text user "9"
			(at -2.50698 1.411732 0)
			(unlocked yes)
			(layer "F.SilkS")
			(effects
				(font
					(size 0.635 0.4064)
					(thickness 0.1524)
				)
			)
		)
		(fp_text user "12"
			(at 3.9624 0.611632 0)
			(unlocked yes)
			(layer "F.SilkS")
			(effects
				(font
					(size 0.635 0.4064)
					(thickness 0.1524)
				)
			)
		)
		(fp_text user "20"
			(at 1.58496 -3.434588 0)
			(unlocked yes)
			(layer "F.SilkS")
			(effects
				(font
					(size 0.635 0.4064)
					(thickness 0.1524)
				)
			)
		)
		(fp_text user "21_22"
			(at -0.53086 -4.237228 0)
			(unlocked yes)
			(layer "F.SilkS")
			(effects
				(font
					(size 0.635 0.4064)
					(thickness 0.1524)
				)
			)
		)
		(fp_text user "11"
			(at 1.1938 3.329432 270)
			(unlocked yes)
			(layer "F.Fab")
			(effects
				(font
					(size 0.635 0.4064)
					(thickness 0.1524)
				)
			)
		)
		(fp_text user "10"
			(at -1.4224 3.253232 270)
			(unlocked yes)
			(layer "F.Fab")
			(effects
				(font
					(size 0.635 0.4064)
					(thickness 0.1524)
				)
			)
		)
		(fp_text user "12"
			(at 2.207768 2.7178 180)
			(unlocked yes)
			(layer "F.Fab")
			(effects
				(font
					(size 0.635 0.4064)
					(thickness 0.1524)
				)
			)
		)
		(fp_text user "9"
			(at -2.338832 2.5908 180)
			(unlocked yes)
			(layer "F.Fab")
			(effects
				(font
					(size 0.635 0.4064)
					(thickness 0.1524)
				)
			)
		)
		(fp_text user "20"
			(at 2.055368 -2.7686 180)
			(unlocked yes)
			(layer "F.Fab")
			(effects
				(font
					(size 0.635 0.4064)
					(thickness 0.1524)
				)
			)
		)
		(fp_text user "21_22"
			(at -0.0762 -3.401568 270)
			(unlocked yes)
			(layer "F.Fab")
			(effects
				(font
					(size 0.635 0.4064)
					(thickness 0.1524)
				)
			)
		)
		(pad "1" smd circle
			(at -1.374902 -1.999996 180)
			(size 0 0)
			(layers "F.Cu" "F.Mask" "F.Paste")
			(net "P12V_OCP_EN_1_R2")
		)
		(pad "2" smd rect
			(at -1.400048 -1.500124 180)
			(size 0.254 0.8128)
			(layers "F.Cu" "F.Mask" "F.Paste")
			(net "GND")
		)
		(pad "3" smd rect
			(at -1.400048 -0.999998 180)
			(size 0.254 0.8128)
			(layers "F.Cu" "F.Mask" "F.Paste")
			(net "GND")
		)
		(pad "4" smd rect
			(at -1.400048 -0.499872 180)
			(size 0.254 0.8128)
			(layers "F.Cu" "F.Mask" "F.Paste")
			(net "P12V_OCP_TIMER_1")
		)
		(pad "5" smd rect
			(at -1.400048 0 180)
			(size 0.254 0.8128)
			(layers "F.Cu" "F.Mask" "F.Paste")
			(net "P12V_OCP_ISET_1")
		)
		(pad "6" smd rect
			(at -1.400048 0.499872 180)
			(size 0.254 0.8128)
			(layers "F.Cu" "F.Mask" "F.Paste")
			(net "P12V_OCP_SS_1")
		)
		(pad "7" smd rect
			(at -1.400048 0.999998 180)
			(size 0.254 0.8128)
			(layers "F.Cu" "F.Mask" "F.Paste")
			(net "GND")
		)
		(pad "8" smd rect
			(at -1.400048 1.500124 180)
			(size 0.254 0.8128)
			(layers "F.Cu" "F.Mask" "F.Paste")
			(net "P12V_OCP_IMON_1")
		)
		(pad "9" smd rect
			(at -1.400048 1.999996 180)
			(size 0.254 0.8128)
			(layers "F.Cu" "F.Mask" "F.Paste")
			(net "P12V_OCP_FLTB_1")
		)
		(pad "10" smd rect
			(at -0.499872 2.400046 270)
			(size 0.254 0.8128)
			(layers "F.Cu" "F.Mask" "F.Paste")
			(net "HP_LVC3_OCP_V3_1_P12V_PWRGD")
		)
		(pad "11" smd rect
			(at 0.499872 2.400046 270)
			(size 0.254 0.8128)
			(layers "F.Cu" "F.Mask" "F.Paste")
			(net "P12V_OCP_OV_FB_1")
		)
		(pad "12" smd rect
			(at 1.400048 1.999996 180)
			(size 0.254 0.8128)
			(layers "F.Cu" "F.Mask" "F.Paste")
			(net "P12V_OCP_AVIN_PD_1")
		)
		(pad "13" smd rect
			(at 1.400048 1.500124 180)
			(size 0.254 0.8128)
			(layers "F.Cu" "F.Mask" "F.Paste")
			(net "P12V_OCP_SFF")
		)
		(pad "14" smd rect
			(at 1.400048 0.999998 180)
			(size 0.254 0.8128)
			(layers "F.Cu" "F.Mask" "F.Paste")
			(net "P12V_OCP_SFF")
		)
		(pad "15" smd rect
			(at 1.400048 0.499872 180)
			(size 0.254 0.8128)
			(layers "F.Cu" "F.Mask" "F.Paste")
			(net "P12V_OCP_SFF")
		)
		(pad "16" smd rect
			(at 1.400048 0 180)
			(size 0.254 0.8128)
			(layers "F.Cu" "F.Mask" "F.Paste")
			(net "P12V_OCP_SFF")
		)
		(pad "17" smd rect
			(at 1.400048 -0.499872 180)
			(size 0.254 0.8128)
			(layers "F.Cu" "F.Mask" "F.Paste")
			(net "P12V_OCP_SFF")
		)
		(pad "18" smd rect
			(at 1.400048 -0.999998 180)
			(size 0.254 0.8128)
			(layers "F.Cu" "F.Mask" "F.Paste")
			(net "P12V_OCP_SFF")
		)
		(pad "19" smd rect
			(at 1.400048 -1.500124 180)
			(size 0.254 0.8128)
			(layers "F.Cu" "F.Mask" "F.Paste")
			(net "P12V_OCP_SFF")
		)
		(pad "20" smd rect
			(at 1.400048 -1.999996 180)
			(size 0.254 0.8128)
			(layers "F.Cu" "F.Mask" "F.Paste")
			(net "P12V_OCP_SFF")
		)
		(pad "21_22" smd circle
			(at 0.499872 -2.337562 180)
			(size 0 0)
			(layers "F.Cu" "F.Mask" "F.Paste")
			(net "P12V_AUX")
		)
		(pad "23" smd rect
			(at 0 -1.100074 180)
			(size 0.254 1.27)
			(layers "F.Cu" "F.Mask" "F.Paste")
			(net "P12V_AUX")
		)
		(pad "24" smd rect
			(at 0 -0.199898 180)
			(size 0.254 1.27)
			(layers "F.Cu" "F.Mask" "F.Paste")
			(net "P12V_AUX")
		)
		(pad "25" smd rect
			(at 0 0.700024 180)
			(size 0.254 1.27)
			(layers "F.Cu" "F.Mask" "F.Paste")
			(net "P12V_AUX")
		)
		(pad "26" smd rect
			(at 0 1.599946 180)
			(size 0.254 1.27)
			(layers "F.Cu" "F.Mask" "F.Paste")
			(net "P12V_AUX")
		)
	)
	(footprint ""
		(layer "F.Cu")
		(at 267.38707 -92.63253 -90)
		(property "Reference" "R1305"
			(at 0 0 270)
			(layer "F.SilkS")
			(hide yes)
			(effects
				(font
					(size 1.27 1.27)
				)
			)
		)
		(property "Value" ""
			(at 0 0 270)
			(layer "F.Fab")
			(effects
				(font
					(size 1.27 1.27)
				)
			)
		)
		(duplicate_pad_numbers_are_jumpers no)
		(fp_line
			(start -0.7874 0.4064)
			(end -0.7874 -0.4064)
			(stroke
				(width 0.1524)
				(type default)
			)
			(layer "F.SilkS")
		)
		(fp_line
			(start 0.7874 0.4064)
			(end -0.7874 0.4064)
			(stroke
				(width 0.1524)
				(type default)
			)
			(layer "F.SilkS")
		)
		(fp_line
			(start -0.7874 -0.4064)
			(end 0.7874 -0.4064)
			(stroke
				(width 0.1524)
				(type default)
			)
			(layer "F.SilkS")
		)
		(fp_line
			(start 0.7874 -0.4064)
			(end 0.7874 0.4064)
			(stroke
				(width 0.1524)
				(type default)
			)
			(layer "F.SilkS")
		)
		(fp_line
			(start -0.67945 0.3048)
			(end -0.67945 -0.305054)
			(stroke
				(width 0.1)
				(type default)
			)
			(layer "F.Fab")
		)
		(fp_line
			(start -0.12065 0.3048)
			(end -0.67945 0.3048)
			(stroke
				(width 0.1)
				(type default)
			)
			(layer "F.Fab")
		)
		(fp_line
			(start 0.120396 0.3048)
			(end 0.120396 0.2794)
			(stroke
				(width 0.1)
				(type default)
			)
			(layer "F.Fab")
		)
		(fp_line
			(start 0.67945 0.3048)
			(end 0.120396 0.3048)
			(stroke
				(width 0.1)
				(type default)
			)
			(layer "F.Fab")
		)
		(fp_line
			(start -0.12065 0.2794)
			(end -0.12065 0.3048)
			(stroke
				(width 0.1)
				(type default)
			)
			(layer "F.Fab")
		)
		(fp_line
			(start 0.120396 0.2794)
			(end -0.12065 0.2794)
			(stroke
				(width 0.1)
				(type default)
			)
			(layer "F.Fab")
		)
		(fp_line
			(start -0.12065 -0.2794)
			(end 0.12065 -0.2794)
			(stroke
				(width 0.1)
				(type default)
			)
			(layer "F.Fab")
		)
		(fp_line
			(start 0.12065 -0.2794)
			(end 0.12065 -0.3048)
			(stroke
				(width 0.1)
				(type default)
			)
			(layer "F.Fab")
		)
		(fp_line
			(start 0.12065 -0.3048)
			(end 0.67945 -0.3048)
			(stroke
				(width 0.1)
				(type default)
			)
			(layer "F.Fab")
		)
		(fp_line
			(start 0.67945 -0.3048)
			(end 0.67945 0.3048)
			(stroke
				(width 0.1)
				(type default)
			)
			(layer "F.Fab")
		)
		(fp_line
			(start -0.67945 -0.305054)
			(end -0.12065 -0.305054)
			(stroke
				(width 0.1)
				(type default)
			)
			(layer "F.Fab")
		)
		(fp_line
			(start -0.12065 -0.305054)
			(end -0.12065 -0.2794)
			(stroke
				(width 0.1)
				(type default)
			)
			(layer "F.Fab")
		)
		(pad "1" smd circle
			(at -0.40005 0 270)
			(size 0 0)
			(layers "F.Cu" "F.Mask" "F.Paste")
			(net "P3V3_AUX")
		)
		(pad "2" smd circle
			(at 0.40005 0 270)
			(size 0 0)
			(layers "F.Cu" "F.Mask" "F.Paste")
			(net "FM_PLD_CLKS_DEV_EN")
		)
	)
	(footprint ""
		(layer "F.Cu")
		(at 115.951 -56.479948 180)
		(property "Reference" "R4633"
			(at 0 0 180)
			(layer "F.SilkS")
			(hide yes)
			(effects
				(font
					(size 1.27 1.27)
				)
			)
		)
		(property "Value" ""
			(at 0 0 180)
			(layer "F.Fab")
			(effects
				(font
					(size 1.27 1.27)
				)
			)
		)
		(duplicate_pad_numbers_are_jumpers no)
		(fp_line
			(start 0.7874 0.4064)
			(end -0.7874 0.4064)
			(stroke
				(width 0.1524)
				(type default)
			)
			(layer "F.SilkS")
		)
		(fp_line
			(start 0.7874 -0.4064)
			(end 0.7874 0.4064)
			(stroke
				(width 0.1524)
				(type default)
			)
			(layer "F.SilkS")
		)
		(fp_line
			(start -0.7874 0.4064)
			(end -0.7874 -0.4064)
			(stroke
				(width 0.1524)
				(type default)
			)
			(layer "F.SilkS")
		)
		(fp_line
			(start -0.7874 -0.4064)
			(end 0.7874 -0.4064)
			(stroke
				(width 0.1524)
				(type default)
			)
			(layer "F.SilkS")
		)
		(fp_line
			(start 0.67945 0.3048)
			(end 0.120396 0.3048)
			(stroke
				(width 0.1)
				(type default)
			)
			(layer "F.Fab")
		)
		(fp_line
			(start 0.67945 -0.3048)
			(end 0.67945 0.3048)
			(stroke
				(width 0.1)
				(type default)
			)
			(layer "F.Fab")
		)
		(fp_line
			(start 0.12065 -0.2794)
			(end 0.12065 -0.3048)
			(stroke
				(width 0.1)
				(type default)
			)
			(layer "F.Fab")
		)
		(fp_line
			(start 0.12065 -0.3048)
			(end 0.67945 -0.3048)
			(stroke
				(width 0.1)
				(type default)
			)
			(layer "F.Fab")
		)
		(fp_line
			(start 0.120396 0.3048)
			(end 0.120396 0.2794)
			(stroke
				(width 0.1)
				(type default)
			)
			(layer "F.Fab")
		)
		(fp_line
			(start 0.120396 0.2794)
			(end -0.12065 0.2794)
			(stroke
				(width 0.1)
				(type default)
			)
			(layer "F.Fab")
		)
		(fp_line
			(start -0.12065 0.3048)
			(end -0.67945 0.3048)
			(stroke
				(width 0.1)
				(type default)
			)
			(layer "F.Fab")
		)
		(fp_line
			(start -0.12065 0.2794)
			(end -0.12065 0.3048)
			(stroke
				(width 0.1)
				(type default)
			)
			(layer "F.Fab")
		)
		(fp_line
			(start -0.12065 -0.2794)
			(end 0.12065 -0.2794)
			(stroke
				(width 0.1)
				(type default)
			)
			(layer "F.Fab")
		)
		(fp_line
			(start -0.12065 -0.305054)
			(end -0.12065 -0.2794)
			(stroke
				(width 0.1)
				(type default)
			)
			(layer "F.Fab")
		)
		(fp_line
			(start -0.67945 0.3048)
			(end -0.67945 -0.305054)
			(stroke
				(width 0.1)
				(type default)
			)
			(layer "F.Fab")
		)
		(fp_line
			(start -0.67945 -0.305054)
			(end -0.12065 -0.305054)
			(stroke
				(width 0.1)
				(type default)
			)
			(layer "F.Fab")
		)
		(pad "1" smd circle
			(at -0.40005 0 180)
			(size 0 0)
			(layers "F.Cu" "F.Mask" "F.Paste")
			(net "JTAG_BMC_SW_TCK_R")
		)
		(pad "2" smd circle
			(at 0.40005 0 180)
			(size 0 0)
			(layers "F.Cu" "F.Mask" "F.Paste")
			(net "JTAG_BMC_SW_TCK")
		)
	)
)
